# S9S_MB_2U (Grand Teton) — schematic netlist excerpt (pin names and nets, part order shuffled) for the footprints in the layout excerpt that follows; sources: Cadence DE-HDL packaged netlist, KiCad conversion of 03242023_DA0F0TMBIJ0_F0T_Motherboard_J_brd_V01_OCP.brd

C152  Q_CAP_DIFFBUS  DIFF BUS_0.22UF 6.3V 20% X6S  pkg C0201  page 178 : \1\ = DMI_CPU0_PCH_TX_C_DP<1> ; \2\ = DMI_CPU0_PCH_TX_DP<1>

Q148  MOSFET_NCH_DUAL  PJT138K IC  pkg SOT363XD  page 145
  S1  = GND
  G1  = HGX_DETECT_N
  D2  = HGX_DETECT_N_ISO
  S2  = GND
  G2  = HGX_DETECT
  D1  = HGX_DETECT

PL45  Q_INDUCTOR  100NH/16A IND  pkg SMLF  page 259 : \1\ = P12V_AUX ; \2\ = SW_P3V3_AUX_FLT

(kicad_pcb
	(version 20260206)
	(generator "pcbnew")
	(generator_version "10.0")
	(general
		(thickness 1.6)
		(legacy_teardrops no)
	)
	(paper "A4")
	(title_block
		(title "03242023_DA0F0TMBIJ0_F0T_Motherboard_J_brd_V01_OCP.brd")
		(comment 1 "Grand Teton / footprints 3846-3848 of 6105")
	)
	(layers
		(0 "F.Cu" signal "TOP")
		(4 "In1.Cu" signal "GND")
		(6 "In2.Cu" signal "IN1")
		(8 "In3.Cu" signal "GND1")
		(10 "In4.Cu" signal "IN2")
		(12 "In5.Cu" signal "GND2")
		(14 "In6.Cu" signal "IN3")
		(16 "In7.Cu" signal "GND3")
		(18 "In8.Cu" signal "VCC")
		(20 "In9.Cu" signal "VCC1")
		(22 "In10.Cu" signal "GND4")
		(24 "In11.Cu" signal "IN4")
		(26 "In12.Cu" signal "GND5")
		(28 "In13.Cu" signal "IN5")
		(30 "In14.Cu" signal "GND6")
		(32 "In15.Cu" signal "IN6")
		(34 "In16.Cu" signal "GND7")
		(2 "B.Cu" signal "BOTTOM")
		(9 "F.Adhes" user "F.Adhesive")
		(11 "B.Adhes" user "B.Adhesive")
		(13 "F.Paste" user "Package Geometry/Pastemask Top")
		(15 "B.Paste" user "Package Geometry/Pastemask Bottom")
		(5 "F.SilkS" user "Ref Des/Silkscreen Top")
		(7 "B.SilkS" user "Ref Des/Silkscreen Bottom")
		(1 "F.Mask" user "Board Geometry/Soldermask Top")
		(3 "B.Mask" user "Board Geometry/Soldermask Bottom")
		(17 "Dwgs.User" user "User.Drawings")
		(19 "Cmts.User" user "User.Comments")
		(21 "Eco1.User" user "User.Eco1")
		(23 "Eco2.User" user "User.Eco2")
		(25 "Edge.Cuts" user "Board Geometry/Outline")
		(27 "Margin" user)
		(31 "F.CrtYd" user "Package Geometry/Place Bound Top")
		(29 "B.CrtYd" user "Package Geometry/Place Bound Bottom")
		(35 "F.Fab" user "Ref Des/Assembly Top")
		(33 "B.Fab" user "Ref Des/Assembly Bottom")
	)
	(footprint ""
		(layer "F.Cu")
		(at 343.73439 -70.52056 90)
		(property "Reference" "C152"
			(at 0 0 90)
			(layer "F.SilkS")
			(hide yes)
			(effects
				(font
					(size 1.27 1.27)
				)
			)
		)
		(property "Value" ""
			(at 0 0 90)
			(layer "F.Fab")
			(effects
				(font
					(size 1.27 1.27)
				)
			)
		)
		(duplicate_pad_numbers_are_jumpers no)
		(fp_line
			(start 0.299974 -0.150114)
			(end 0.299974 0.150114)
			(stroke
				(width 0.1)
				(type default)
			)
			(layer "F.Fab")
		)
		(fp_line
			(start -0.299974 -0.150114)
			(end 0.299974 -0.150114)
			(stroke
				(width 0.1)
				(type default)
			)
			(layer "F.Fab")
		)
		(fp_line
			(start 0.299974 0.150114)
			(end -0.299974 0.150114)
			(stroke
				(width 0.1)
				(type default)
			)
			(layer "F.Fab")
		)
		(fp_line
			(start -0.299974 0.150114)
			(end -0.299974 -0.150114)
			(stroke
				(width 0.1)
				(type default)
			)
			(layer "F.Fab")
		)
		(pad "1" smd rect
			(at -0.2667 0 90)
			(size 0.3048 0.381)
			(layers "F.Cu" "F.Mask" "F.Paste")
			(net "DMI_CPU0_PCH_TX_C_DP<1>")
		)
		(pad "2" smd rect
			(at 0.2667 0 90)
			(size 0.3048 0.381)
			(layers "F.Cu" "F.Mask" "F.Paste")
			(net "DMI_CPU0_PCH_TX_DP<1>")
		)
	)
	(footprint ""
		(layer "F.Cu")
		(at 465.089748 -62.166246 90)
		(property "Reference" "PL45"
			(at -0.437388 -6.243828 0)
			(unlocked yes)
			(layer "F.SilkS")
			(effects
				(font
					(size 0.7874 0.5842)
					(thickness 0.1524)
				)
				(justify left)
			)
		)
		(property "Value" ""
			(at 0 0 90)
			(layer "F.Fab")
			(effects
				(font
					(size 1.27 1.27)
				)
			)
		)
		(duplicate_pad_numbers_are_jumpers no)
		(fp_line
			(start 2.249932 -2.249932)
			(end 2.249932 -1.3843)
			(stroke
				(width 0.1524)
				(type default)
			)
			(layer "F.SilkS")
		)
		(fp_line
			(start -2.249932 -2.249932)
			(end 2.249932 -2.249932)
			(stroke
				(width 0.1524)
				(type default)
			)
			(layer "F.SilkS")
		)
		(fp_line
			(start -2.249932 -1.3843)
			(end -2.249932 -2.249932)
			(stroke
				(width 0.1524)
				(type default)
			)
			(layer "F.SilkS")
		)
		(fp_line
			(start 2.249932 1.3843)
			(end 2.249932 2.249932)
			(stroke
				(width 0.1524)
				(type default)
			)
			(layer "F.SilkS")
		)
		(fp_line
			(start 2.249932 2.249932)
			(end -2.249932 2.249932)
			(stroke
				(width 0.1524)
				(type default)
			)
			(layer "F.SilkS")
		)
		(fp_line
			(start -2.249932 2.249932)
			(end -2.249932 1.3843)
			(stroke
				(width 0.1524)
				(type default)
			)
			(layer "F.SilkS")
		)
		(fp_line
			(start 2.249932 -2.249932)
			(end 2.249932 2.249932)
			(stroke
				(width 0.1)
				(type default)
			)
			(layer "F.Fab")
		)
		(fp_line
			(start -2.249932 -2.249932)
			(end 2.249932 -2.249932)
			(stroke
				(width 0.1)
				(type default)
			)
			(layer "F.Fab")
		)
		(fp_line
			(start 2.249932 2.249932)
			(end -2.249932 2.249932)
			(stroke
				(width 0.1)
				(type default)
			)
			(layer "F.Fab")
		)
		(fp_line
			(start -2.249932 2.249932)
			(end -2.249932 -2.249932)
			(stroke
				(width 0.1)
				(type default)
			)
			(layer "F.Fab")
		)
		(pad "1" smd rect
			(at -1.82499 0 90)
			(size 1.0668 2.5146)
			(layers "F.Cu" "F.Mask" "F.Paste")
			(net "P12V_AUX")
		)
		(pad "2" smd rect
			(at 1.82499 0 90)
			(size 1.0668 2.5146)
			(layers "F.Cu" "F.Mask" "F.Paste")
			(net "SW_P3V3_AUX_FLT")
		)
	)
	(footprint ""
		(layer "F.Cu")
		(at 94.20606 -414.218628 90)
		(property "Reference" "Q148"
			(at -2.023872 -0.03556 0)
			(unlocked yes)
			(layer "F.SilkS")
			(effects
				(font
					(size 0.7874 0.5842)
					(thickness 0.1524)
				)
				(justify left)
			)
		)
		(property "Value" ""
			(at 0 0 90)
			(layer "F.Fab")
			(effects
				(font
					(size 1.27 1.27)
				)
			)
		)
		(duplicate_pad_numbers_are_jumpers no)
		(fp_line
			(start 1.332738 -1.100074)
			(end 1.332738 1.100074)
			(stroke
				(width 0.1524)
				(type default)
			)
			(layer "F.SilkS")
		)
		(fp_line
			(start 0.4826 -1.100074)
			(end 1.332738 -1.100074)
			(stroke
				(width 0.1524)
				(type default)
			)
			(layer "F.SilkS")
		)
		(fp_line
			(start -0.4826 -1.100074)
			(end 0 -0.541274)
			(stroke
				(width 0.1524)
				(type default)
			)
			(layer "F.SilkS")
		)
		(fp_line
			(start -1.332738 -1.100074)
			(end -0.4826 -1.100074)
			(stroke
				(width 0.1524)
				(type default)
			)
			(layer "F.SilkS")
		)
		(fp_line
			(start 0 -0.541274)
			(end 0.4826 -1.100074)
			(stroke
				(width 0.1524)
				(type default)
			)
			(layer "F.SilkS")
		)
		(fp_line
			(start 1.332738 1.100074)
			(end -1.332738 1.100074)
			(stroke
				(width 0.1524)
				(type default)
			)
			(layer "F.SilkS")
		)
		(fp_line
			(start -1.332738 1.100074)
			(end -1.332738 -1.100074)
			(stroke
				(width 0.1524)
				(type default)
			)
			(layer "F.SilkS")
		)
		(fp_poly
			(pts
				(xy -2.27838 -1.082294) (xy -1.576324 -0.731266) (xy -2.27838 -0.380238)
			)
			(stroke
				(width 0)
				(type default)
			)
			(fill yes)
			(layer "F.SilkS")
		)
		(fp_line
			(start 0.674878 -1.100074)
			(end 0.674878 1.100074)
			(stroke
				(width 0.1)
				(type default)
			)
			(layer "F.Fab")
		)
		(fp_line
			(start -0.674878 -1.100074)
			(end 0.674878 -1.100074)
			(stroke
				(width 0.1)
				(type default)
			)
			(layer "F.Fab")
		)
		(fp_line
			(start 0.674878 1.100074)
			(end -0.674878 1.100074)
			(stroke
				(width 0.1)
				(type default)
			)
			(layer "F.Fab")
		)
		(fp_line
			(start -0.674878 1.100074)
			(end -0.674878 -1.100074)
			(stroke
				(width 0.1)
				(type default)
			)
			(layer "F.Fab")
		)
		(fp_poly
			(pts
				(xy -2.2352 -0.298958) (xy -2.2352 -1.001014) (xy -1.533144 -0.649986)
			)
			(stroke
				(width 0)
				(type default)
			)
			(fill yes)
			(layer "F.Fab")
		)
		(pad "1" smd rect
			(at -0.94996 -0.649986 180)
			(size 0.4318 0.508)
			(layers "F.Cu" "F.Mask" "F.Paste")
			(net "GND")
		)
		(pad "2" smd rect
			(at -0.94996 0 180)
			(size 0.4318 0.508)
			(layers "F.Cu" "F.Mask" "F.Paste")
			(net "HGX_DETECT_N")
		)
		(pad "3" smd rect
			(at -0.94996 0.649986 180)
			(size 0.4318 0.508)
			(layers "F.Cu" "F.Mask" "F.Paste")
			(net "HGX_DETECT_N_ISO")
		)
		(pad "4" smd rect
			(at 0.94996 0.649986 180)
			(size 0.4318 0.508)
			(layers "F.Cu" "F.Mask" "F.Paste")
			(net "GND")
		)
		(pad "5" smd rect
			(at 0.94996 0 180)
			(size 0.4318 0.508)
			(layers "F.Cu" "F.Mask" "F.Paste")
			(net "HGX_DETECT")
		)
		(pad "6" smd rect
			(at 0.94996 -0.649986 180)
			(size 0.4318 0.508)
			(layers "F.Cu" "F.Mask" "F.Paste")
			(net "HGX_DETECT")
		)
	)
)
